FILE_TYPE = CONNECTIVITY;
{Allegro Design Entry HDL 16.6-p007 (v16-6-112F) 10/10/2012}
"PAGE_NUMBER" = 8;
0"NC";
END.
